(kicad_pcb
	(version 20260206)
	(generator "pcbnew")
	(generator_version "10.0")
	(general
		(thickness 1.6)
		(legacy_teardrops no)
	)
	(paper "A4")
	(title_block
		(title "04192023_DAF0TMB3IC0_F0TG_MB_C_brd_V02_OCP.brd")
		(comment 1 "Grand Teton / footprints 4661-4666 of 8354")
	)
	(layers
		(0 "F.Cu" signal "TOP")
		(4 "In1.Cu" signal "GND")
		(6 "In2.Cu" signal "IN1")
		(8 "In3.Cu" signal "GND1")
		(10 "In4.Cu" signal "IN2")
		(12 "In5.Cu" signal "GND2")
		(14 "In6.Cu" signal "IN3")
		(16 "In7.Cu" signal "GND3")
		(18 "In8.Cu" signal "VCC")
		(20 "In9.Cu" signal "VCC1")
		(22 "In10.Cu" signal "GND4")
		(24 "In11.Cu" signal "IN4")
		(26 "In12.Cu" signal "GND5")
		(28 "In13.Cu" signal "IN5")
		(30 "In14.Cu" signal "GND6")
		(32 "In15.Cu" signal "IN6")
		(34 "In16.Cu" signal "GND7")
		(2 "B.Cu" signal "BOTTOM")
		(9 "F.Adhes" user "F.Adhesive")
		(11 "B.Adhes" user "B.Adhesive")
		(13 "F.Paste" user "Package Geometry/Pastemask Top")
		(15 "B.Paste" user "Package Geometry/Pastemask Bottom")
		(5 "F.SilkS" user "Ref Des/Silkscreen Top")
		(7 "B.SilkS" user "Ref Des/Silkscreen Bottom")
		(1 "F.Mask" user "Board Geometry/Soldermask Top")
		(3 "B.Mask" user "Board Geometry/Soldermask Bottom")
		(17 "Dwgs.User" user "User.Drawings")
		(19 "Cmts.User" user "User.Comments")
		(21 "Eco1.User" user "User.Eco1")
		(23 "Eco2.User" user "User.Eco2")
		(25 "Edge.Cuts" user "Board Geometry/Outline")
		(27 "Margin" user)
		(31 "F.CrtYd" user "Package Geometry/Place Bound Top")
		(29 "B.CrtYd" user "Package Geometry/Place Bound Bottom")
		(35 "F.Fab" user "Ref Des/Assembly Top")
		(33 "B.Fab" user "Ref Des/Assembly Bottom")
	)
	(footprint ""
		(layer "F.Cu")
		(at 94.338648 -69.488558 90)
		(property "Reference" "PC2137"
			(at 0 0 90)
			(layer "F.SilkS")
			(hide yes)
			(effects
				(font
					(size 1.27 1.27)
				)
			)
		)
		(property "Value" ""
			(at 0 0 90)
			(layer "F.Fab")
			(effects
				(font
					(size 1.27 1.27)
				)
			)
		)
		(duplicate_pad_numbers_are_jumpers no)
		(fp_line
			(start 0.7874 -0.4064)
			(end 0.7874 0.4064)
			(stroke
				(width 0.1524)
				(type default)
			)
			(layer "F.SilkS")
		)
		(fp_line
			(start -0.7874 -0.4064)
			(end 0.7874 -0.4064)
			(stroke
				(width 0.1524)
				(type default)
			)
			(layer "F.SilkS")
		)
		(fp_line
			(start 0.7874 0.4064)
			(end -0.7874 0.4064)
			(stroke
				(width 0.1524)
				(type default)
			)
			(layer "F.SilkS")
		)
		(fp_line
			(start -0.7874 0.4064)
			(end -0.7874 -0.4064)
			(stroke
				(width 0.1524)
				(type default)
			)
			(layer "F.SilkS")
		)
		(fp_line
			(start -0.12065 -0.305054)
			(end -0.12065 -0.2794)
			(stroke
				(width 0.1)
				(type default)
			)
			(layer "F.Fab")
		)
		(fp_line
			(start -0.67945 -0.305054)
			(end -0.12065 -0.305054)
			(stroke
				(width 0.1)
				(type default)
			)
			(layer "F.Fab")
		)
		(fp_line
			(start 0.67945 -0.3048)
			(end 0.67945 0.3048)
			(stroke
				(width 0.1)
				(type default)
			)
			(layer "F.Fab")
		)
		(fp_line
			(start 0.12065 -0.3048)
			(end 0.67945 -0.3048)
			(stroke
				(width 0.1)
				(type default)
			)
			(layer "F.Fab")
		)
		(fp_line
			(start 0.12065 -0.2794)
			(end 0.12065 -0.3048)
			(stroke
				(width 0.1)
				(type default)
			)
			(layer "F.Fab")
		)
		(fp_line
			(start -0.12065 -0.2794)
			(end 0.12065 -0.2794)
			(stroke
				(width 0.1)
				(type default)
			)
			(layer "F.Fab")
		)
		(fp_line
			(start 0.120396 0.2794)
			(end -0.12065 0.2794)
			(stroke
				(width 0.1)
				(type default)
			)
			(layer "F.Fab")
		)
		(fp_line
			(start -0.12065 0.2794)
			(end -0.12065 0.3048)
			(stroke
				(width 0.1)
				(type default)
			)
			(layer "F.Fab")
		)
		(fp_line
			(start 0.67945 0.3048)
			(end 0.120396 0.3048)
			(stroke
				(width 0.1)
				(type default)
			)
			(layer "F.Fab")
		)
		(fp_line
			(start 0.120396 0.3048)
			(end 0.120396 0.2794)
			(stroke
				(width 0.1)
				(type default)
			)
			(layer "F.Fab")
		)
		(fp_line
			(start -0.12065 0.3048)
			(end -0.67945 0.3048)
			(stroke
				(width 0.1)
				(type default)
			)
			(layer "F.Fab")
		)
		(fp_line
			(start -0.67945 0.3048)
			(end -0.67945 -0.305054)
			(stroke
				(width 0.1)
				(type default)
			)
			(layer "F.Fab")
		)
		(pad "1" smd circle
			(at -0.40005 0 90)
			(size 0 0)
			(layers "F.Cu" "F.Mask" "F.Paste")
			(net "P3V3_OCP_V3_2_R")
		)
		(pad "2" smd circle
			(at 0.40005 0 90)
			(size 0 0)
			(layers "F.Cu" "F.Mask" "F.Paste")
			(net "GND")
		)
	)
	(footprint ""
		(layer "F.Cu")
		(at 182.9562 -96.103948 90)
		(property "Reference" "R488"
			(at 0 0 90)
			(layer "F.SilkS")
			(hide yes)
			(effects
				(font
					(size 1.27 1.27)
				)
			)
		)
		(property "Value" ""
			(at 0 0 90)
			(layer "F.Fab")
			(effects
				(font
					(size 1.27 1.27)
				)
			)
		)
		(duplicate_pad_numbers_are_jumpers no)
		(fp_line
			(start 0.7874 -0.4064)
			(end 0.7874 0.4064)
			(stroke
				(width 0.1524)
				(type default)
			)
			(layer "F.SilkS")
		)
		(fp_line
			(start -0.7874 -0.4064)
			(end 0.7874 -0.4064)
			(stroke
				(width 0.1524)
				(type default)
			)
			(layer "F.SilkS")
		)
		(fp_line
			(start 0.7874 0.4064)
			(end -0.7874 0.4064)
			(stroke
				(width 0.1524)
				(type default)
			)
			(layer "F.SilkS")
		)
		(fp_line
			(start -0.7874 0.4064)
			(end -0.7874 -0.4064)
			(stroke
				(width 0.1524)
				(type default)
			)
			(layer "F.SilkS")
		)
		(fp_line
			(start -0.12065 -0.305054)
			(end -0.12065 -0.2794)
			(stroke
				(width 0.1)
				(type default)
			)
			(layer "F.Fab")
		)
		(fp_line
			(start -0.67945 -0.305054)
			(end -0.12065 -0.305054)
			(stroke
				(width 0.1)
				(type default)
			)
			(layer "F.Fab")
		)
		(fp_line
			(start 0.67945 -0.3048)
			(end 0.67945 0.3048)
			(stroke
				(width 0.1)
				(type default)
			)
			(layer "F.Fab")
		)
		(fp_line
			(start 0.12065 -0.3048)
			(end 0.67945 -0.3048)
			(stroke
				(width 0.1)
				(type default)
			)
			(layer "F.Fab")
		)
		(fp_line
			(start 0.12065 -0.2794)
			(end 0.12065 -0.3048)
			(stroke
				(width 0.1)
				(type default)
			)
			(layer "F.Fab")
		)
		(fp_line
			(start -0.12065 -0.2794)
			(end 0.12065 -0.2794)
			(stroke
				(width 0.1)
				(type default)
			)
			(layer "F.Fab")
		)
		(fp_line
			(start 0.120396 0.2794)
			(end -0.12065 0.2794)
			(stroke
				(width 0.1)
				(type default)
			)
			(layer "F.Fab")
		)
		(fp_line
			(start -0.12065 0.2794)
			(end -0.12065 0.3048)
			(stroke
				(width 0.1)
				(type default)
			)
			(layer "F.Fab")
		)
		(fp_line
			(start 0.67945 0.3048)
			(end 0.120396 0.3048)
			(stroke
				(width 0.1)
				(type default)
			)
			(layer "F.Fab")
		)
		(fp_line
			(start 0.120396 0.3048)
			(end 0.120396 0.2794)
			(stroke
				(width 0.1)
				(type default)
			)
			(layer "F.Fab")
		)
		(fp_line
			(start -0.12065 0.3048)
			(end -0.67945 0.3048)
			(stroke
				(width 0.1)
				(type default)
			)
			(layer "F.Fab")
		)
		(fp_line
			(start -0.67945 0.3048)
			(end -0.67945 -0.305054)
			(stroke
				(width 0.1)
				(type default)
			)
			(layer "F.Fab")
		)
		(pad "1" smd circle
			(at -0.40005 0 90)
			(size 0 0)
			(layers "F.Cu" "F.Mask" "F.Paste")
			(net "CPU1_THERMTRIP_N")
		)
		(pad "2" smd circle
			(at 0.40005 0 90)
			(size 0 0)
			(layers "F.Cu" "F.Mask" "F.Paste")
			(net "CPU1_THERMTRIP_R_N")
		)
	)
	(footprint ""
		(layer "F.Cu")
		(at 6.029198 -135.388096)
		(property "Reference" "Y8003"
			(at -1.6002 -3.17373 0)
			(unlocked yes)
			(layer "F.SilkS")
			(effects
				(font
					(size 0.7874 0.5842)
					(thickness 0.1524)
				)
				(justify left)
			)
		)
		(property "Value" ""
			(at 0 0 0)
			(layer "F.Fab")
			(effects
				(font
					(size 1.27 1.27)
				)
			)
		)
		(duplicate_pad_numbers_are_jumpers no)
		(fp_line
			(start -1.5367 -1.9558)
			(end 1.5367 -1.9558)
			(stroke
				(width 0.1524)
				(type default)
			)
			(layer "F.SilkS")
		)
		(fp_line
			(start -1.5367 1.9558)
			(end -1.5367 -1.9558)
			(stroke
				(width 0.1524)
				(type default)
			)
			(layer "F.SilkS")
		)
		(fp_line
			(start 1.5367 -1.9558)
			(end 1.5367 1.9558)
			(stroke
				(width 0.1524)
				(type default)
			)
			(layer "F.SilkS")
		)
		(fp_line
			(start 1.5367 1.9558)
			(end -1.5367 1.9558)
			(stroke
				(width 0.1524)
				(type default)
			)
			(layer "F.SilkS")
		)
		(fp_poly
			(pts
				(xy -1.6129 -1.9558) (xy -0.1778 -1.9558) (xy -0.1778 -2.54) (xy -1.6129 -2.54)
			)
			(stroke
				(width 0)
				(type default)
			)
			(fill yes)
			(layer "F.SilkS")
		)
		(fp_line
			(start -1.299972 -1.649984)
			(end 1.299972 -1.649984)
			(stroke
				(width 0.1)
				(type default)
			)
			(layer "F.Fab")
		)
		(fp_line
			(start -1.299972 1.649984)
			(end -1.299972 -1.649984)
			(stroke
				(width 0.1)
				(type default)
			)
			(layer "F.Fab")
		)
		(fp_line
			(start 1.299972 -1.649984)
			(end 1.299972 1.649984)
			(stroke
				(width 0.1)
				(type default)
			)
			(layer "F.Fab")
		)
		(fp_line
			(start 1.299972 1.649984)
			(end -1.299972 1.649984)
			(stroke
				(width 0.1)
				(type default)
			)
			(layer "F.Fab")
		)
		(fp_poly
			(pts
				(xy -1.6129 -1.9558) (xy -0.1778 -1.9558) (xy -0.1778 -2.54) (xy -1.6129 -2.54)
			)
			(stroke
				(width 0)
				(type default)
			)
			(fill yes)
			(layer "F.Fab")
		)
		(pad "1" smd rect
			(at -0.8001 -1.100074)
			(size 1.2192 1.4224)
			(layers "F.Cu" "F.Mask" "F.Paste")
			(net "CLK_GEN2_XTAL_IN_R")
		)
		(pad "2" smd rect
			(at -0.8001 1.100074)
			(size 1.2192 1.4224)
			(layers "F.Cu" "F.Mask" "F.Paste")
			(net "GND")
		)
		(pad "3" smd rect
			(at 0.8001 1.100074)
			(size 1.2192 1.4224)
			(layers "F.Cu" "F.Mask" "F.Paste")
			(net "CLK_GEN2_XTAL_OUT")
		)
		(pad "4" smd rect
			(at 0.8001 -1.100074)
			(size 1.2192 1.4224)
			(layers "F.Cu" "F.Mask" "F.Paste")
			(net "GND")
		)
	)
	(footprint ""
		(layer "F.Cu")
		(at 220.190822 -56.835802 180)
		(property "Reference" "R3760"
			(at 0 0 180)
			(layer "F.SilkS")
			(hide yes)
			(effects
				(font
					(size 1.27 1.27)
				)
			)
		)
		(property "Value" ""
			(at 0 0 180)
			(layer "F.Fab")
			(effects
				(font
					(size 1.27 1.27)
				)
			)
		)
		(duplicate_pad_numbers_are_jumpers no)
		(fp_line
			(start 0.7874 0.4064)
			(end -0.7874 0.4064)
			(stroke
				(width 0.1524)
				(type default)
			)
			(layer "F.SilkS")
		)
		(fp_line
			(start 0.7874 -0.4064)
			(end 0.7874 0.4064)
			(stroke
				(width 0.1524)
				(type default)
			)
			(layer "F.SilkS")
		)
		(fp_line
			(start -0.7874 0.4064)
			(end -0.7874 -0.4064)
			(stroke
				(width 0.1524)
				(type default)
			)
			(layer "F.SilkS")
		)
		(fp_line
			(start -0.7874 -0.4064)
			(end 0.7874 -0.4064)
			(stroke
				(width 0.1524)
				(type default)
			)
			(layer "F.SilkS")
		)
		(fp_line
			(start 0.67945 0.3048)
			(end 0.120396 0.3048)
			(stroke
				(width 0.1)
				(type default)
			)
			(layer "F.Fab")
		)
		(fp_line
			(start 0.67945 -0.3048)
			(end 0.67945 0.3048)
			(stroke
				(width 0.1)
				(type default)
			)
			(layer "F.Fab")
		)
		(fp_line
			(start 0.12065 -0.2794)
			(end 0.12065 -0.3048)
			(stroke
				(width 0.1)
				(type default)
			)
			(layer "F.Fab")
		)
		(fp_line
			(start 0.12065 -0.3048)
			(end 0.67945 -0.3048)
			(stroke
				(width 0.1)
				(type default)
			)
			(layer "F.Fab")
		)
		(fp_line
			(start 0.120396 0.3048)
			(end 0.120396 0.2794)
			(stroke
				(width 0.1)
				(type default)
			)
			(layer "F.Fab")
		)
		(fp_line
			(start 0.120396 0.2794)
			(end -0.12065 0.2794)
			(stroke
				(width 0.1)
				(type default)
			)
			(layer "F.Fab")
		)
		(fp_line
			(start -0.12065 0.3048)
			(end -0.67945 0.3048)
			(stroke
				(width 0.1)
				(type default)
			)
			(layer "F.Fab")
		)
		(fp_line
			(start -0.12065 0.2794)
			(end -0.12065 0.3048)
			(stroke
				(width 0.1)
				(type default)
			)
			(layer "F.Fab")
		)
		(fp_line
			(start -0.12065 -0.2794)
			(end 0.12065 -0.2794)
			(stroke
				(width 0.1)
				(type default)
			)
			(layer "F.Fab")
		)
		(fp_line
			(start -0.12065 -0.305054)
			(end -0.12065 -0.2794)
			(stroke
				(width 0.1)
				(type default)
			)
			(layer "F.Fab")
		)
		(fp_line
			(start -0.67945 0.3048)
			(end -0.67945 -0.305054)
			(stroke
				(width 0.1)
				(type default)
			)
			(layer "F.Fab")
		)
		(fp_line
			(start -0.67945 -0.305054)
			(end -0.12065 -0.305054)
			(stroke
				(width 0.1)
				(type default)
			)
			(layer "F.Fab")
		)
		(pad "1" smd circle
			(at -0.40005 0 180)
			(size 0 0)
			(layers "F.Cu" "F.Mask" "F.Paste")
			(net "P3V3_E1S_0")
		)
		(pad "2" smd circle
			(at 0.40005 0 180)
			(size 0 0)
			(layers "F.Cu" "F.Mask" "F.Paste")
			(net "VSENSE_P3V3_INA230_2_INN")
		)
	)
	(footprint ""
		(layer "F.Cu")
		(at 184.622694 -409.128722 180)
		(property "Reference" "PC2188"
			(at 0 0 180)
			(layer "F.SilkS")
			(hide yes)
			(effects
				(font
					(size 1.27 1.27)
				)
			)
		)
		(property "Value" ""
			(at 0 0 180)
			(layer "F.Fab")
			(effects
				(font
					(size 1.27 1.27)
				)
			)
		)
		(duplicate_pad_numbers_are_jumpers no)
		(fp_line
			(start 0.7874 0.4064)
			(end -0.7874 0.4064)
			(stroke
				(width 0.1524)
				(type default)
			)
			(layer "F.SilkS")
		)
		(fp_line
			(start 0.7874 -0.4064)
			(end 0.7874 0.4064)
			(stroke
				(width 0.1524)
				(type default)
			)
			(layer "F.SilkS")
		)
		(fp_line
			(start -0.7874 0.4064)
			(end -0.7874 -0.4064)
			(stroke
				(width 0.1524)
				(type default)
			)
			(layer "F.SilkS")
		)
		(fp_line
			(start -0.7874 -0.4064)
			(end 0.7874 -0.4064)
			(stroke
				(width 0.1524)
				(type default)
			)
			(layer "F.SilkS")
		)
		(fp_line
			(start 0.67945 0.3048)
			(end 0.120396 0.3048)
			(stroke
				(width 0.1)
				(type default)
			)
			(layer "F.Fab")
		)
		(fp_line
			(start 0.67945 -0.3048)
			(end 0.67945 0.3048)
			(stroke
				(width 0.1)
				(type default)
			)
			(layer "F.Fab")
		)
		(fp_line
			(start 0.12065 -0.2794)
			(end 0.12065 -0.3048)
			(stroke
				(width 0.1)
				(type default)
			)
			(layer "F.Fab")
		)
		(fp_line
			(start 0.12065 -0.3048)
			(end 0.67945 -0.3048)
			(stroke
				(width 0.1)
				(type default)
			)
			(layer "F.Fab")
		)
		(fp_line
			(start 0.120396 0.3048)
			(end 0.120396 0.2794)
			(stroke
				(width 0.1)
				(type default)
			)
			(layer "F.Fab")
		)
		(fp_line
			(start 0.120396 0.2794)
			(end -0.12065 0.2794)
			(stroke
				(width 0.1)
				(type default)
			)
			(layer "F.Fab")
		)
		(fp_line
			(start -0.12065 0.3048)
			(end -0.67945 0.3048)
			(stroke
				(width 0.1)
				(type default)
			)
			(layer "F.Fab")
		)
		(fp_line
			(start -0.12065 0.2794)
			(end -0.12065 0.3048)
			(stroke
				(width 0.1)
				(type default)
			)
			(layer "F.Fab")
		)
		(fp_line
			(start -0.12065 -0.2794)
			(end 0.12065 -0.2794)
			(stroke
				(width 0.1)
				(type default)
			)
			(layer "F.Fab")
		)
		(fp_line
			(start -0.12065 -0.305054)
			(end -0.12065 -0.2794)
			(stroke
				(width 0.1)
				(type default)
			)
			(layer "F.Fab")
		)
		(fp_line
			(start -0.67945 0.3048)
			(end -0.67945 -0.305054)
			(stroke
				(width 0.1)
				(type default)
			)
			(layer "F.Fab")
		)
		(fp_line
			(start -0.67945 -0.305054)
			(end -0.12065 -0.305054)
			(stroke
				(width 0.1)
				(type default)
			)
			(layer "F.Fab")
		)
		(pad "1" smd circle
			(at -0.40005 0 180)
			(size 0 0)
			(layers "F.Cu" "F.Mask" "F.Paste")
			(net "P12V_PSU")
		)
		(pad "2" smd circle
			(at 0.40005 0 180)
			(size 0 0)
			(layers "F.Cu" "F.Mask" "F.Paste")
			(net "GND")
		)
	)
	(footprint ""
		(layer "F.Cu")
		(at 393.363958 -325.675752)
		(property "Reference" "R213"
			(at 0 0 0)
			(layer "F.SilkS")
			(hide yes)
			(effects
				(font
					(size 1.27 1.27)
				)
			)
		)
		(property "Value" ""
			(at 0 0 0)
			(layer "F.Fab")
			(effects
				(font
					(size 1.27 1.27)
				)
			)
		)
		(duplicate_pad_numbers_are_jumpers no)
		(fp_line
			(start -0.7874 -0.4064)
			(end 0.7874 -0.4064)
			(stroke
				(width 0.1524)
				(type default)
			)
			(layer "F.SilkS")
		)
		(fp_line
			(start -0.7874 0.4064)
			(end -0.7874 -0.4064)
			(stroke
				(width 0.1524)
				(type default)
			)
			(layer "F.SilkS")
		)
		(fp_line
			(start 0.7874 -0.4064)
			(end 0.7874 0.4064)
			(stroke
				(width 0.1524)
				(type default)
			)
			(layer "F.SilkS")
		)
		(fp_line
			(start 0.7874 0.4064)
			(end -0.7874 0.4064)
			(stroke
				(width 0.1524)
				(type default)
			)
			(layer "F.SilkS")
		)
		(fp_line
			(start -0.67945 -0.305054)
			(end -0.12065 -0.305054)
			(stroke
				(width 0.1)
				(type default)
			)
			(layer "F.Fab")
		)
		(fp_line
			(start -0.67945 0.3048)
			(end -0.67945 -0.305054)
			(stroke
				(width 0.1)
				(type default)
			)
			(layer "F.Fab")
		)
		(fp_line
			(start -0.12065 -0.305054)
			(end -0.12065 -0.2794)
			(stroke
				(width 0.1)
				(type default)
			)
			(layer "F.Fab")
		)
		(fp_line
			(start -0.12065 -0.2794)
			(end 0.12065 -0.2794)
			(stroke
				(width 0.1)
				(type default)
			)
			(layer "F.Fab")
		)
		(fp_line
			(start -0.12065 0.2794)
			(end -0.12065 0.3048)
			(stroke
				(width 0.1)
				(type default)
			)
			(layer "F.Fab")
		)
		(fp_line
			(start -0.12065 0.3048)
			(end -0.67945 0.3048)
			(stroke
				(width 0.1)
				(type default)
			)
			(layer "F.Fab")
		)
		(fp_line
			(start 0.120396 0.2794)
			(end -0.12065 0.2794)
			(stroke
				(width 0.1)
				(type default)
			)
			(layer "F.Fab")
		)
		(fp_line
			(start 0.120396 0.3048)
			(end 0.120396 0.2794)
			(stroke
				(width 0.1)
				(type default)
			)
			(layer "F.Fab")
		)
		(fp_line
			(start 0.12065 -0.3048)
			(end 0.67945 -0.3048)
			(stroke
				(width 0.1)
				(type default)
			)
			(layer "F.Fab")
		)
		(fp_line
			(start 0.12065 -0.2794)
			(end 0.12065 -0.3048)
			(stroke
				(width 0.1)
				(type default)
			)
			(layer "F.Fab")
		)
		(fp_line
			(start 0.67945 -0.3048)
			(end 0.67945 0.3048)
			(stroke
				(width 0.1)
				(type default)
			)
			(layer "F.Fab")
		)
		(fp_line
			(start 0.67945 0.3048)
			(end 0.120396 0.3048)
			(stroke
				(width 0.1)
				(type default)
			)
			(layer "F.Fab")
		)
		(pad "1" smd circle
			(at -0.40005 0)
			(size 0 0)
			(layers "F.Cu" "F.Mask" "F.Paste")
			(net "SMB_CPU_5_R_SDA")
		)
		(pad "2" smd circle
			(at 0.40005 0)
			(size 0 0)
			(layers "F.Cu" "F.Mask" "F.Paste")
			(net "SMB_CPU_5_SDA")
		)
	)
)
